(kicad_pcb
	(version 20221018)
	(generator pcbnew)
	(general
    (thickness 1.562)
  )
	(paper "A4")
	(title_block
    (title "Thunderbolt PCIe Adaper")
    (date "2024-07-09")
    (rev "1.0.3")
    (comment 1 "www.antmicro.com")
    (comment 2 "Antmicro Ltd.")
		(comment 9 "footprints 133-141 of 271")
	)
	(layers
    (0 "F.Cu" signal)
    (1 "In1.Cu" signal)
    (2 "In2.Cu" signal)
    (3 "In3.Cu" signal)
    (4 "In4.Cu" signal)
    (31 "B.Cu" signal)
    (32 "B.Adhes" user "B.Adhesive")
    (33 "F.Adhes" user "F.Adhesive")
    (34 "B.Paste" user)
    (35 "F.Paste" user)
    (36 "B.SilkS" user "B.Silkscreen")
    (37 "F.SilkS" user "F.Silkscreen")
    (38 "B.Mask" user)
    (39 "F.Mask" user)
    (40 "Dwgs.User" user "User.Drawings")
    (41 "Cmts.User" user "User.Comments")
    (42 "Eco1.User" user "User.Eco1")
    (43 "Eco2.User" user "User.Eco2")
    (44 "Edge.Cuts" user)
    (45 "Margin" user)
    (46 "B.CrtYd" user "B.Courtyard")
    (47 "F.CrtYd" user "F.Courtyard")
    (48 "B.Fab" user)
    (49 "F.Fab" user)
  )
	(footprint "antmicro-footprints:R_0402_1005Metric" (layer "B.Cu")
    (at 146.5 70.94 -90)
    (descr "Resistor SMD 0402")
    (tags "resistor SMD 0402")
    (property "Author" "Antmicro")
    (property "License" "Apache-2.0")
    (property "MPN" "CR0402-FX-1001GLF")
    (property "Manufacturer" "Bourns")
    (property "Sheetfile" "tb-power.kicad_sch")
    (property "Sheetname" "Thunderbolt Controller - Power")
    (property "Tolerance" "1%")
    (property "Val" "1k")
    (property "ki_description" "SMD Chip Resistor, 1 kohm, ± 1%, 63 mW, 0402 [1005 Metric], Thick Film, General Purpose")
    (property "ki_keywords" "0402, SMT, RESISTOR, PASSIVE")
    (attr smd)
    (fp_text reference "R47" (at -3.122 -0.439 90) (layer "B.SilkS")
        (effects (font (size 0.7 0.7) (thickness 0.15)) (justify left bottom mirror))
    )
    (fp_text value "R_1k_0402" (at -1.011843 -1.772047 90) (layer "B.Fab")
        (effects (font (size 0.7 0.7) (thickness 0.15)) (justify left bottom mirror))
    )
    (fp_text user "${REFERENCE}" (at -0.95 -3.168 90) (layer "B.Fab") hide
        (effects (font (size 0.7 0.7) (thickness 0.15)) (justify left bottom mirror))
    )
    (fp_text user "Author: Antmicro" (at -0.95 -4.169 90) (layer "B.Fab") hide
        (effects (font (size 0.7 0.7) (thickness 0.15)) (justify left bottom mirror))
    )
    (fp_text user "License: Apache-2.0" (at -0.95 -5.169 90) (layer "B.Fab") hide
        (effects (font (size 0.7 0.7) (thickness 0.15)) (justify left bottom mirror))
    )
    (fp_rect (start -0.925 0.47) (end 0.925 -0.47)
      (stroke (width 0.05) (type default)) (fill none) (layer "B.CrtYd"))
    (fp_rect (start -0.5 0.25) (end 0.5 -0.25)
      (stroke (width 0.15) (type solid)) (fill none) (layer "B.Fab"))
    (pad "1" smd roundrect (at -0.48 0 270) (size 0.59 0.64) (layers "B.Cu" "B.Paste" "B.Mask") (roundrect_rratio 0.25)
      (net 112 "Net-(U4A-VCC0P9_SVR_SENSE)") (pintype "passive"))
    (pad "2" smd roundrect (at 0.48 0 270) (size 0.59 0.64) (layers "B.Cu" "B.Paste" "B.Mask") (roundrect_rratio 0.25)
      (net 138 "Net-(Q1-B)") (pintype "passive"))
  )
	(footprint "antmicro-footprints:C_0402_1005Metric" (layer "B.Cu")
    (at 136.275 83.275 90)
    (descr "Capacitor SMD 0402")
    (tags "capacitor SMD 0402")
    (property "Author" "Antmicro")
    (property "Dielectric" "")
    (property "License" "Apache-2.0")
    (property "MPN" "C1005X6S1A105K050BC")
    (property "Manufacturer" "TDK")
    (property "Sheetfile" "tb-power.kicad_sch")
    (property "Sheetname" "Thunderbolt Controller - Power")
    (property "Val" "1u")
    (property "Voltage" "")
    (property "ki_description" "SMD Multilayer Ceramic Capacitor, 1 µF, 10 V, 0402 [1005 Metric], ± 10%, X6S, C")
    (property "ki_keywords" "0402, SMT, CAPACITOR, PASSIVE, CERAMIC, MLCC")
    (attr smd)
    (fp_text reference "C69" (at -6.895 16.887 270) (layer "B.SilkS")
        (effects (font (size 0.7 0.7) (thickness 0.15)) (justify left bottom mirror))
    )
    (fp_text value "C_1u_0402" (at -1.022927 -2.155213 270) (layer "B.Fab")
        (effects (font (size 0.7 0.7) (thickness 0.15)) (justify left bottom mirror))
    )
    (fp_text user "Author: Antmicro" (at -0.939 -3.399 270) (layer "B.Fab") hide
        (effects (font (size 0.7 0.7) (thickness 0.15)) (justify left bottom mirror))
    )
    (fp_text user "License: Apache-2.0" (at -0.939 -5.799 270) (layer "B.Fab") hide
        (effects (font (size 0.7 0.7) (thickness 0.15)) (justify left bottom mirror))
    )
    (fp_text user "${REFERENCE}" (at -0.939 -4.599 270) (layer "B.Fab") hide
        (effects (font (size 0.7 0.7) (thickness 0.15)) (justify left bottom mirror))
    )
    (fp_rect (start -0.925 0.47) (end 0.925 -0.47)
      (stroke (width 0.05) (type default)) (fill none) (layer "B.CrtYd"))
    (fp_line (start -0.494 -0.248) (end -0.494 0.25)
      (stroke (width 0.15) (type solid)) (layer "B.Fab"))
    (fp_line (start -0.494 0.25) (end 0.504 0.25)
      (stroke (width 0.15) (type solid)) (layer "B.Fab"))
    (fp_line (start 0.504 -0.248) (end -0.494 -0.248)
      (stroke (width 0.15) (type solid)) (layer "B.Fab"))
    (fp_line (start 0.504 0.25) (end 0.504 -0.248)
      (stroke (width 0.15) (type solid)) (layer "B.Fab"))
    (pad "1" smd roundrect (at -0.48 0 90) (size 0.59 0.64) (layers "B.Cu" "B.Paste" "B.Mask") (roundrect_rratio 0.25)
      (net 1 "GND") (pintype "passive"))
    (pad "2" smd roundrect (at 0.48 0 90) (size 0.59 0.64) (layers "B.Cu" "B.Paste" "B.Mask") (roundrect_rratio 0.25)
      (net 110 "Net-(U4A-VCC3P3_ANA_USB2)") (pintype "passive"))
  )
	(footprint "antmicro-footprints:C_0402_1005Metric" (layer "B.Cu")
    (at 158.91 65.47 -90)
    (descr "Capacitor SMD 0402")
    (tags "capacitor SMD 0402")
    (property "Author" "Antmicro")
    (property "Dielectric" "")
    (property "License" "Apache-2.0")
    (property "MPN" "04025C221JAT2A")
    (property "Manufacturer" "KYOCERA AVX")
    (property "Sheetfile" "power.kicad_sch")
    (property "Sheetname" "Power")
    (property "Val" "220p")
    (property "Voltage" "")
    (property "ki_description" "SMD Multilayer Ceramic Capacitor, 220 pF, 50 V, 0402 [1005 Metric], ± 10%, X7R, MC")
    (property "ki_keywords" "0402, SMT, CAPACITOR, PASSIVE")
    (attr smd)
    (fp_text reference "C49" (at -1.030251 -2.369062 90) (layer "B.SilkS")
        (effects (font (size 0.7 0.7) (thickness 0.15)) (justify left bottom mirror))
    )
    (fp_text value "C_220p_0402" (at -1.022927 -2.155213 90) (layer "B.Fab")
        (effects (font (size 0.7 0.7) (thickness 0.15)) (justify left bottom mirror))
    )
    (fp_text user "Author: Antmicro" (at -0.939 -3.399 90) (layer "B.Fab") hide
        (effects (font (size 0.7 0.7) (thickness 0.15)) (justify left bottom mirror))
    )
    (fp_text user "License: Apache-2.0" (at -0.939 -5.799 90) (layer "B.Fab") hide
        (effects (font (size 0.7 0.7) (thickness 0.15)) (justify left bottom mirror))
    )
    (fp_text user "${REFERENCE}" (at -0.939 -4.599 90) (layer "B.Fab") hide
        (effects (font (size 0.7 0.7) (thickness 0.15)) (justify left bottom mirror))
    )
    (fp_rect (start -0.925 0.47) (end 0.925 -0.47)
      (stroke (width 0.05) (type default)) (fill none) (layer "B.CrtYd"))
    (fp_line (start -0.494 -0.248) (end -0.494 0.25)
      (stroke (width 0.15) (type solid)) (layer "B.Fab"))
    (fp_line (start -0.494 0.25) (end 0.504 0.25)
      (stroke (width 0.15) (type solid)) (layer "B.Fab"))
    (fp_line (start 0.504 -0.248) (end -0.494 -0.248)
      (stroke (width 0.15) (type solid)) (layer "B.Fab"))
    (fp_line (start 0.504 0.25) (end 0.504 -0.248)
      (stroke (width 0.15) (type solid)) (layer "B.Fab"))
    (pad "1" smd roundrect (at -0.48 0 270) (size 0.59 0.64) (layers "B.Cu" "B.Paste" "B.Mask") (roundrect_rratio 0.25)
      (net 1 "GND") (pintype "passive"))
    (pad "2" smd roundrect (at 0.48 0 270) (size 0.59 0.64) (layers "B.Cu" "B.Paste" "B.Mask") (roundrect_rratio 0.25)
      (net 11 "CC1") (pintype "passive"))
  )
	(footprint "antmicro-footprints:R_0402_1005Metric" (layer "B.Cu")
    (at 147.5 70.94 90)
    (descr "Resistor SMD 0402")
    (tags "resistor SMD 0402")
    (property "Author" "Antmicro")
    (property "License" "Apache-2.0")
    (property "MPN" "CR0402-FX-1003GLF")
    (property "Manufacturer" "Bourns")
    (property "Sheetfile" "tb-power.kicad_sch")
    (property "Sheetname" "Thunderbolt Controller - Power")
    (property "Tolerance" "1%")
    (property "Val" "100k")
    (property "ki_description" "SMD Chip Resistor, 100 kohm, ± 1%, 62.5 mW, 0402 [1005 Metric], Thick Film, General Purpose")
    (property "ki_keywords" "0402, SMT, RESISTOR, PASSIVE")
    (attr smd)
    (fp_text reference "R48" (at 3.122 0.455 270) (layer "B.SilkS")
        (effects (font (size 0.7 0.7) (thickness 0.15)) (justify left bottom mirror))
    )
    (fp_text value "R_100k_0402" (at -1.011843 -1.772047 270) (layer "B.Fab")
        (effects (font (size 0.7 0.7) (thickness 0.15)) (justify left bottom mirror))
    )
    (fp_text user "${REFERENCE}" (at -0.95 -3.168 270) (layer "B.Fab") hide
        (effects (font (size 0.7 0.7) (thickness 0.15)) (justify left bottom mirror))
    )
    (fp_text user "License: Apache-2.0" (at -0.95 -5.169 270) (layer "B.Fab") hide
        (effects (font (size 0.7 0.7) (thickness 0.15)) (justify left bottom mirror))
    )
    (fp_text user "Author: Antmicro" (at -0.95 -4.169 270) (layer "B.Fab") hide
        (effects (font (size 0.7 0.7) (thickness 0.15)) (justify left bottom mirror))
    )
    (fp_rect (start -0.925 0.47) (end 0.925 -0.47)
      (stroke (width 0.05) (type default)) (fill none) (layer "B.CrtYd"))
    (fp_rect (start -0.5 0.25) (end 0.5 -0.25)
      (stroke (width 0.15) (type solid)) (fill none) (layer "B.Fab"))
    (pad "1" smd roundrect (at -0.48 0 90) (size 0.59 0.64) (layers "B.Cu" "B.Paste" "B.Mask") (roundrect_rratio 0.25)
      (net 1 "GND") (pintype "passive"))
    (pad "2" smd roundrect (at 0.48 0 90) (size 0.59 0.64) (layers "B.Cu" "B.Paste" "B.Mask") (roundrect_rratio 0.25)
      (net 138 "Net-(Q1-B)") (pintype "passive"))
  )
	(footprint "antmicro-footprints:R_0402_1005Metric" (layer "B.Cu")
    (at 116.45 64.675 90)
    (descr "Resistor SMD 0402")
    (tags "resistor SMD 0402")
    (property "Author" "Antmicro")
    (property "License" "Apache-2.0")
    (property "MPN" "CR0402-FX-1003GLF")
    (property "Manufacturer" "Bourns")
    (property "Sheetfile" "power.kicad_sch")
    (property "Sheetname" "Power")
    (property "Tolerance" "1%")
    (property "Val" "100k")
    (property "ki_description" "SMD Chip Resistor, 100 kohm, ± 1%, 62.5 mW, 0402 [1005 Metric], Thick Film, General Purpose")
    (property "ki_keywords" "0402, SMT, RESISTOR, PASSIVE")
    (attr smd)
    (fp_text reference "R23" (at -0.984 0.39 270) (layer "B.SilkS")
        (effects (font (size 0.7 0.7) (thickness 0.15)) (justify left bottom mirror))
    )
    (fp_text value "R_100k_0402" (at -1.011843 -1.772047 270) (layer "B.Fab")
        (effects (font (size 0.7 0.7) (thickness 0.15)) (justify left bottom mirror))
    )
    (fp_text user "Author: Antmicro" (at -0.95 -4.169 270) (layer "B.Fab") hide
        (effects (font (size 0.7 0.7) (thickness 0.15)) (justify left bottom mirror))
    )
    (fp_text user "${REFERENCE}" (at -0.95 -3.168 270) (layer "B.Fab") hide
        (effects (font (size 0.7 0.7) (thickness 0.15)) (justify left bottom mirror))
    )
    (fp_text user "License: Apache-2.0" (at -0.95 -5.169 270) (layer "B.Fab") hide
        (effects (font (size 0.7 0.7) (thickness 0.15)) (justify left bottom mirror))
    )
    (fp_rect (start -0.925 0.47) (end 0.925 -0.47)
      (stroke (width 0.05) (type default)) (fill none) (layer "B.CrtYd"))
    (fp_rect (start -0.5 0.25) (end 0.5 -0.25)
      (stroke (width 0.15) (type solid)) (fill none) (layer "B.Fab"))
    (pad "1" smd roundrect (at -0.48 0 90) (size 0.59 0.64) (layers "B.Cu" "B.Paste" "B.Mask") (roundrect_rratio 0.25)
      (net 158 "Net-(U2-PG)") (pintype "passive"))
    (pad "2" smd roundrect (at 0.48 0 90) (size 0.59 0.64) (layers "B.Cu" "B.Paste" "B.Mask") (roundrect_rratio 0.25)
      (net 6 "/Power/SMPS_LDO") (pintype "passive"))
  )
	(footprint "antmicro-footprints:R_0402_1005Metric" (layer "B.Cu")
    (at 140.3 66.82 -90)
    (descr "Resistor SMD 0402")
    (tags "resistor SMD 0402")
    (property "Author" "Antmicro")
    (property "License" "Apache-2.0")
    (property "MPN" "CR0402-FX-3301GLF")
    (property "Manufacturer" "Bourns")
    (property "Sheetfile" "connectors.kicad_sch")
    (property "Sheetname" "Connectors")
    (property "Tolerance" "1%")
    (property "Val" "3k3")
    (property "ki_description" "SMD Chip Resistor, 3.3 kohm, ± 1%, 63 mW, 0402 [1005 Metric], Thick Film, General Purpose")
    (property "ki_keywords" "0402, SMT, RESISTOR, PASSIVE")
    (attr smd)
    (fp_text reference "R1" (at -3.066 -0.416 90) (layer "B.SilkS")
        (effects (font (size 0.7 0.7) (thickness 0.15)) (justify left bottom mirror))
    )
    (fp_text value "R_3k3_0402" (at -1.011843 -1.772047 90) (layer "B.Fab")
        (effects (font (size 0.7 0.7) (thickness 0.15)) (justify left bottom mirror))
    )
    (fp_text user "${REFERENCE}" (at -0.95 -3.168 90) (layer "B.Fab") hide
        (effects (font (size 0.7 0.7) (thickness 0.15)) (justify left bottom mirror))
    )
    (fp_text user "Author: Antmicro" (at -0.95 -4.169 90) (layer "B.Fab") hide
        (effects (font (size 0.7 0.7) (thickness 0.15)) (justify left bottom mirror))
    )
    (fp_text user "License: Apache-2.0" (at -0.95 -5.169 90) (layer "B.Fab") hide
        (effects (font (size 0.7 0.7) (thickness 0.15)) (justify left bottom mirror))
    )
    (fp_rect (start -0.925 0.47) (end 0.925 -0.47)
      (stroke (width 0.05) (type default)) (fill none) (layer "B.CrtYd"))
    (fp_rect (start -0.5 0.25) (end 0.5 -0.25)
      (stroke (width 0.15) (type solid)) (fill none) (layer "B.Fab"))
    (pad "1" smd roundrect (at -0.48 0 270) (size 0.59 0.64) (layers "B.Cu" "B.Paste" "B.Mask") (roundrect_rratio 0.25)
      (net 1 "GND") (pintype "passive"))
    (pad "2" smd roundrect (at 0.48 0 270) (size 0.59 0.64) (layers "B.Cu" "B.Paste" "B.Mask") (roundrect_rratio 0.25)
      (net 43 "PCIE_PWRGD") (pintype "passive"))
  )
	(footprint "antmicro-footprints:C_0402_1005Metric" (layer "B.Cu")
    (at 155.41 63.97)
    (descr "Capacitor SMD 0402")
    (tags "capacitor SMD 0402")
    (property "Author" "Antmicro")
    (property "Dielectric" "")
    (property "License" "Apache-2.0")
    (property "MPN" "C1005X6S1A105K050BC")
    (property "Manufacturer" "TDK")
    (property "Sheetfile" "power.kicad_sch")
    (property "Sheetname" "Power")
    (property "Val" "1u")
    (property "Voltage" "")
    (property "ki_description" "SMD Multilayer Ceramic Capacitor, 1 µF, 10 V, 0402 [1005 Metric], ± 10%, X6S, C")
    (property "ki_keywords" "0402, SMT, CAPACITOR, PASSIVE, CERAMIC, MLCC")
    (attr smd)
    (fp_text reference "C34" (at 1.152793 1.433548 180) (layer "B.SilkS")
        (effects (font (size 0.7 0.7) (thickness 0.15)) (justify left bottom mirror))
    )
    (fp_text value "C_1u_0402" (at -1.022927 -2.155213 180) (layer "B.Fab")
        (effects (font (size 0.7 0.7) (thickness 0.15)) (justify left bottom mirror))
    )
    (fp_text user "${REFERENCE}" (at -0.939 -4.599 180) (layer "B.Fab") hide
        (effects (font (size 0.7 0.7) (thickness 0.15)) (justify left bottom mirror))
    )
    (fp_text user "Author: Antmicro" (at -0.939 -3.399 180) (layer "B.Fab") hide
        (effects (font (size 0.7 0.7) (thickness 0.15)) (justify left bottom mirror))
    )
    (fp_text user "License: Apache-2.0" (at -0.939 -5.799 180) (layer "B.Fab") hide
        (effects (font (size 0.7 0.7) (thickness 0.15)) (justify left bottom mirror))
    )
    (fp_rect (start -0.925 0.47) (end 0.925 -0.47)
      (stroke (width 0.05) (type default)) (fill none) (layer "B.CrtYd"))
    (fp_line (start -0.494 -0.248) (end -0.494 0.25)
      (stroke (width 0.15) (type solid)) (layer "B.Fab"))
    (fp_line (start -0.494 0.25) (end 0.504 0.25)
      (stroke (width 0.15) (type solid)) (layer "B.Fab"))
    (fp_line (start 0.504 -0.248) (end -0.494 -0.248)
      (stroke (width 0.15) (type solid)) (layer "B.Fab"))
    (fp_line (start 0.504 0.25) (end 0.504 -0.248)
      (stroke (width 0.15) (type solid)) (layer "B.Fab"))
    (pad "1" smd roundrect (at -0.48 0) (size 0.59 0.64) (layers "B.Cu" "B.Paste" "B.Mask") (roundrect_rratio 0.25)
      (net 101 "Net-(U3-VOUT_3V3)") (pintype "passive"))
    (pad "2" smd roundrect (at 0.48 0) (size 0.59 0.64) (layers "B.Cu" "B.Paste" "B.Mask") (roundrect_rratio 0.25)
      (net 1 "GND") (pintype "passive"))
  )
	(footprint "antmicro-footprints:R_0402_1005Metric" (layer "B.Cu")
    (at 155.41 61.97 180)
    (descr "Resistor SMD 0402")
    (tags "resistor SMD 0402")
    (property "Author" "Antmicro")
    (property "License" "Apache-2.0")
    (property "MPN" "CR0402-FX-1004GLF")
    (property "Manufacturer" "Bourns")
    (property "Sheetfile" "power.kicad_sch")
    (property "Sheetname" "Power")
    (property "Tolerance" "1%")
    (property "Val" "1M")
    (property "ki_description" "SMD Chip Resistor, 1 Mohm, ± 1%, 62.5 mW, 0402 [1005 Metric], Thick Film, General Purpose")
    (property "ki_keywords" "0402, SMT, RESISTOR, PASSIVE")
    (attr smd)
    (fp_text reference "R21" (at -2.832 -0.4505) (layer "B.SilkS")
        (effects (font (size 0.7 0.7) (thickness 0.15)) (justify left bottom mirror))
    )
    (fp_text value "R_1M_0402" (at -1.011843 -1.772047) (layer "B.Fab")
        (effects (font (size 0.7 0.7) (thickness 0.15)) (justify left bottom mirror))
    )
    (fp_text user "${REFERENCE}" (at -0.95 -3.168) (layer "B.Fab") hide
        (effects (font (size 0.7 0.7) (thickness 0.15)) (justify left bottom mirror))
    )
    (fp_text user "License: Apache-2.0" (at -0.95 -5.169) (layer "B.Fab") hide
        (effects (font (size 0.7 0.7) (thickness 0.15)) (justify left bottom mirror))
    )
    (fp_text user "Author: Antmicro" (at -0.95 -4.169) (layer "B.Fab") hide
        (effects (font (size 0.7 0.7) (thickness 0.15)) (justify left bottom mirror))
    )
    (fp_rect (start -0.925 0.47) (end 0.925 -0.47)
      (stroke (width 0.05) (type default)) (fill none) (layer "B.CrtYd"))
    (fp_rect (start -0.5 0.25) (end 0.5 -0.25)
      (stroke (width 0.15) (type solid)) (fill none) (layer "B.Fab"))
    (pad "1" smd roundrect (at -0.48 0 180) (size 0.59 0.64) (layers "B.Cu" "B.Paste" "B.Mask") (roundrect_rratio 0.25)
      (net 1 "GND") (pintype "passive"))
    (pad "2" smd roundrect (at 0.48 0 180) (size 0.59 0.64) (layers "B.Cu" "B.Paste" "B.Mask") (roundrect_rratio 0.25)
      (net 156 "Net-(U3-UART_RX)") (pintype "passive"))
  )
	(footprint "antmicro-footprints:C_0402_1005Metric" (layer "B.Cu")
    (at 136.5 92.65 -90)
    (descr "Capacitor SMD 0402")
    (tags "capacitor SMD 0402")
    (property "Author" "Antmicro")
    (property "Dielectric" "")
    (property "License" "Apache-2.0")
    (property "MPN" "CC0402KRX5R6BB224")
    (property "Manufacturer" "YAGEO")
    (property "Sheetfile" "tb.kicad_sch")
    (property "Sheetname" "TB Controller")
    (property "Val" "220n")
    (property "Voltage" "")
    (property "ki_description" "SMD Multilayer Ceramic Capacitor, 0.22 µF, 10 V, 0402 [1005 Metric], ± 10%, X5R, CC Series")
    (property "ki_keywords" "0402, SMT, CAPACITOR, PASSIVE, MLCC, CERAMIC")
    (attr smd)
    (fp_text reference "C107" (at -3.877 -0.47 90) (layer "B.SilkS")
        (effects (font (size 0.7 0.7) (thickness 0.15)) (justify left bottom mirror))
    )
    (fp_text value "C_220n_0402" (at -1.022927 -2.155213 90) (layer "B.Fab")
        (effects (font (size 0.7 0.7) (thickness 0.15)) (justify left bottom mirror))
    )
    (fp_text user "${REFERENCE}" (at -0.939 -4.599 90) (layer "B.Fab") hide
        (effects (font (size 0.7 0.7) (thickness 0.15)) (justify left bottom mirror))
    )
    (fp_text user "Author: Antmicro" (at -0.939 -3.399 90) (layer "B.Fab") hide
        (effects (font (size 0.7 0.7) (thickness 0.15)) (justify left bottom mirror))
    )
    (fp_text user "License: Apache-2.0" (at -0.939 -5.799 90) (layer "B.Fab") hide
        (effects (font (size 0.7 0.7) (thickness 0.15)) (justify left bottom mirror))
    )
    (fp_rect (start -0.925 0.47) (end 0.925 -0.47)
      (stroke (width 0.05) (type default)) (fill none) (layer "B.CrtYd"))
    (fp_line (start -0.494 -0.248) (end -0.494 0.25)
      (stroke (width 0.15) (type solid)) (layer "B.Fab"))
    (fp_line (start -0.494 0.25) (end 0.504 0.25)
      (stroke (width 0.15) (type solid)) (layer "B.Fab"))
    (fp_line (start 0.504 -0.248) (end -0.494 -0.248)
      (stroke (width 0.15) (type solid)) (layer "B.Fab"))
    (fp_line (start 0.504 0.25) (end 0.504 -0.248)
      (stroke (width 0.15) (type solid)) (layer "B.Fab"))
    (pad "1" smd roundrect (at -0.48 0 270) (size 0.59 0.64) (layers "B.Cu" "B.Paste" "B.Mask") (roundrect_rratio 0.25)
      (net 78 "/TB Controller/TX2_N") (pintype "passive"))
    (pad "2" smd roundrect (at 0.48 0 270) (size 0.59 0.64) (layers "B.Cu" "B.Paste" "B.Mask") (roundrect_rratio 0.25)
      (net 26 "PCIE_TX2_N") (pintype "passive"))
  )
)
